FILE_TYPE = MULTI_PHYS_TABLE;

PART 'MOSFET_NCH_DUAL'

{========================================================================================}
:VALUE          | PART_TYPE | MATERIAL | PART_NUMBER       = STANDARD        | LIFECYCLE      | PART_NUMBER       | JEDEC_TYPE             | DESCRIPTION                                | MANUFTR | MANUF_PN       | RD_CMPLS_LVL | CMPLS_LVL | CLASS | DIP_SMD | FP_ECN             | FROM_PJ        | DATA                              | EE_CHECK_LIST | PSL | PREFERENCE | CREATOR | CREATEDAY  | STATUS ;
{========================================================================================}
 'NTZD3154NT1H' | 'SMLF'    | 'IC'     | 'BAM31540000'(!)  = 'End of Design' | 'Comp-Approve' | 'BAM31540000'     |'SOT563-6'| 'TRANS MOSFET NTZD3154NT1H(20V,540MA),HF'  | 'ONS'   | 'NTZD3154NT1H' | 'EP(V1)'     | 'EP(V1)'  | 'IC'  | ''      | ''                 | 'S1S-MICHAEL'  | 'ONS_NTZD3154N.pdf'               | ''            | ''  | ''         | ''      | '20120419' | ''    
 'NTZD3154NT1H' | 'SMLF'    | 'EMPTY'  | 'BAM31540000'(!)  = 'End of Design' | 'Comp-Approve' | 'BAM31540000'     |'SOT563-6'| 'TRANS MOSFET NTZD3154NT1H(20V,540MA),HF'  | 'ONS'   | 'NTZD3154NT1H' | 'EP(V1)'     | 'EP(V1)'  | 'IC'  | ''      | ''                 | 'S1S-MICHAEL'  | 'ONS_NTZD3154N.pdf'               | ''            | ''  | ''         | ''      | '20120419' | ''    
 'NTZD3154NT1G' | 'SMLF'    | 'IC'     | 'BAM31540003'(!)  = 'End of Design' | 'Comp-Approve' | 'BAM31540003'     |'SOT563-6'| 'TRANS MOSFET NTZD3154NT1G(20V,540MA)'     | 'ONS'   | 'NTZD3154NT1G' | 'EU'         | 'EU'      | 'IC'  | ''      | ''                 | 'T6V-KOOL'     | 'ONS_NTZD3154NT1G.pdf'            | ''            | ''  | ''         | ''      | '20120421' | ''    
 'NTZD3154NT1G' | 'SMLF'    | 'EMPTY'  | 'BAM31540003'(!)  = 'End of Design' | 'Comp-Approve' | 'BAM31540003'     |'SOT563-6'| 'TRANS MOSFET NTZD3154NT1G(20V,540MA)'     | 'ONS'   | 'NTZD3154NT1G' | 'EU'         | 'EU'      | 'IC'  | ''      | ''                 | 'T6V-KOOL'     | 'ONS_NTZD3154NT1G.pdf'            | ''            | ''  | ''         | ''      | '20120421' | ''    
 'BSS138DW-7-F' | 'SMLF'    | 'IC'     | 'BAM01380032'(!)  = ''              | ''             | 'BAM01380032'     |'SOT363A'| 'TRANS MOSFET BSS138DW-7-F(50V.200MA)'     | 'DDS'   | 'BSS138DW-7-F' | 'EP(V1)'     | ''        | 'IC'  | ''      | ''                 | 'S2N-JUMP'     | 'BSS138DW-7-F.pdf'                | ''            | ''  | ''         | ''      | '20120425' | ''    
 'BSS138DW-7-F' | 'SMLF'    | 'EMPTY'  | 'BAM01380032'(!)  = ''              | ''             | 'BAM01380032'     |'SOT363A'| 'TRANS MOSFET BSS138DW-7-F(50V.200MA)'     | 'DDS'   | 'BSS138DW-7-F' | 'EP(V1)'     | ''        | 'IC'  | ''      | ''                 | 'S2N-JUMP'     | 'BSS138DW-7-F.pdf'                | ''            | ''  | ''         | ''      | '20120425' | ''    
 'DMN2400UV-7'  | 'SMLF'    | 'IC'     | 'BAM24000000'(!)  = ''              | ''             | 'BAM24000000'     |'SOT563-6XA'| 'TRANS MOS DMN2400UV-7(20V,1.33A,0.53W)'   | 'DDS'   | 'DMN2400UV-7'  | 'EP(V1)'     | 'EP(V1)'  | 'IC'  | ''      | ''                 | 'S1N-AI-JU'    | 'DDS_DMN2400UV.pdf'               | ''            | ''  | ''         | ''      | '20121022' | ''    
 'DMN2400UV-7'  | 'SMLF'    | 'EMPTY'  | 'BAM24000000'(!)  = ''              | ''             | 'BAM24000000'     |'SOT563-6XA'| 'TRANS MOS DMN2400UV-7(20V,1.33A,0.53W)'   | 'DDS'   | 'DMN2400UV-7'  | 'EP(V1)'     | 'EP(V1)'  | 'IC'  | ''      | ''                 | 'S1N-AI-JU'    | 'DDS_DMN2400UV.pdf'               | ''            | ''  | ''         | ''      | '20121022' | ''    
 'NX7002AKS'    | 'SMLF'    | 'IC'     | 'BAM70020069'(!)  = 'End of Design' | 'Comp-Approve' | 'BAM70020069'     |'SOT363XB'| 'TRANS MOSFET NX7002AKS(60V,170MA,1.06W)'  | 'NXP'   | 'NX7002AKS'    | 'EP(V1)'     | ''        | 'IC'  | ''      | ''                 | 'S1N-AI-JU'    | 'NXP_NX7002AKS.pdf'               | ''            | ''  | ''         | ''      | '20121129' | ''    
 'NX7002AKS'    | 'SMLF'    | 'EMPTY'  | 'BAM70020069'(!)  = 'End of Design' | 'Comp-Approve' | 'BAM70020069'     |'SOT363XB'| 'TRANS MOSFET NX7002AKS(60V,170MA,1.06W)'  | 'NXP'   | 'NX7002AKS'    | 'EP(V1)'     | ''        | 'IC'  | ''      | ''                 | 'S1N-AI-JU'    | 'NXP_NX7002AKS.pdf'               | ''            | ''  | ''         | ''      | '20121129' | ''    
 'BSS138BKS'    | 'SMLF'    | 'IC'     | 'BAM01380017'(!)  = ''              | ''             | 'BAM01380017'     |'SOT363XB'| 'TRANS MOSFET BSS138BKS(60V,0.32A,0.445W)' | 'NXP'   | 'BSS138BKS'    | 'EP(V1)'     | ''        | 'IC'  | ''      | ''                 | 'S2B-YU-LIN'   | 'NXP_BSS138BKS.pdf'               | ''            | ''  | ''         | ''      | '20121218' | ''    
 'BSS138BKS'    | 'SMLF'    | 'EMPTY'  | 'BAM01380017'(!)  = ''              | ''             | 'BAM01380017'     |'SOT363XB'| 'TRANS MOSFET BSS138BKS(60V,0.32A,0.445W)' | 'NXP'   | 'BSS138BKS'    | 'EP(V1)'     | ''        | 'IC'  | ''      | ''                 | 'S2B-YU-LIN'   | 'NXP_BSS138BKS.pdf'               | ''            | ''  | ''         | ''      | '20121218' | ''    
 '2N7002DWKX-7' | 'SMLF'    | 'IC'     | 'BAM70020079'(!)  = 'Potential'     | 'End of Life'  | 'BAM70020079'     |'SOT363XA_EOL'| 'TR MOS 2N7002DWKX-7(60V115MA,0.2W)SOT363' | 'DDS'   | '2N7002DWKX-7' | 'EP(V1)'     | 'EP(V1)'  | 'IC'  | ''      | ''                 | 'S4LZ-ROGER'   | 'DDS_2N7002DWKX-7.pdf'            | ''            | ''  | ''         | ''      | '20140506' | ''    
 '2N7002DWKX-7' | 'SMLF'    | 'EMPTY'  | 'BAM70020079'(!)  = 'Potential'     | 'End of Life'  | 'BAM70020079'     |'SOT363XA_EOL'| 'TR MOS 2N7002DWKX-7(60V115MA,0.2W)SOT363' | 'DDS'   | '2N7002DWKX-7' | 'EP(V1)'     | 'EP(V1)'  | 'IC'  | ''      | ''                 | 'S4LZ-ROGER'   | 'DDS_2N7002DWKX-7.pdf'            | ''            | ''  | ''         | ''      | '20140506' | ''    
 'NTJD4001NT1G' | 'SMLF'    | 'IC'     | 'BAM40010011'(!)  = 'End of Design' | 'Comp-Approve' | 'BAM40010011'     |'SOT363'| 'TRANS MOS NTJD4001NT1G(30V,0.25A)SC-88'   | 'ONS'   | 'NTJD4001NT1G' | 'EU'         | 'EU'      | 'IC'  | ''      | ''                 | 'T2R-GAVEN '   | 'ONS_NTJD4001N.pdf'               | ''            | ''  | ''         | ''      | '20140710' | ''    
 'NTJD4001NT1G' | 'SMLF'    | 'EMPTY'  | 'BAM40010011'(!)  = 'End of Design' | 'Comp-Approve' | 'BAM40010011'     |'SOT363'| 'TRANS MOS NTJD4001NT1G(30V,0.25A)SC-88'   | 'ONS'   | 'NTJD4001NT1G' | 'EU'         | 'EU'      | 'IC'  | ''      | ''                 | 'T2R-GAVEN '   | 'ONS_NTJD4001N.pdf'               | ''            | ''  | ''         | ''      | '20140710' | ''    
 '2N7002KDW'    | 'SMLF'    | 'IC'     | 'BAM70020047'(!)  = ''              | ''             | 'BAM70020047'     |'SOT363XD'| 'TRANS MOS 2N7002KDW(60V115MA,0.2W)SOT363' | 'PJT'   | '2N7002KDW'    | 'EP(V1)'     | 'EP(V1)'  | 'IC'  | ''      | ''                 | 'F06-GLEN'     | 'ONS_NTJD4001N.pdf'               | ''            | ''  | ''         | ''      | '20140923' | ''    
 '2N7002KDW'    | 'SMLF'    | 'EMPTY'  | 'BAM70020047'(!)  = ''              | ''             | 'BAM70020047'     |'SOT363XD'| 'TRANS MOS 2N7002KDW(60V115MA,0.2W)SOT363' | 'PJT'   | '2N7002KDW'    | 'EP(V1)'     | 'EP(V1)'  | 'IC'  | ''      | ''                 | 'F06-GLEN'     | 'ONS_NTJD4001N.pdf'               | ''            | ''  | ''         | ''      | '20140923' | ''    
 'PJT138K'      | 'SMLF'    | 'IC'     | 'BAM138K0003'(!)  = ''              | ''             | 'BAM138K0003'     |'SOT363XD'| 'TRANS MOSFET PJT138K(50V,0.36A,0.236W)'   | 'PJT'   | 'PJT138K'      | 'EP(V1)'     | 'EP(V1)'  | 'IC'  | ''      | ''                 | 'F09-MARK'     | 'PJT_PJT138K_revJULY-25-2013.pdf' | ''            | ''  | ''         | ''      | '20160617' | ''    
 'PJT138K'      | 'SMLF'    | 'EMPTY'  | 'BAM138K0003'(!)  = ''              | ''             | 'BAM138K0003'     |'SOT363XD'| 'TRANS MOSFET PJT138K(50V,0.36A,0.236W)'   | 'PJT'   | 'PJT138K'      | 'EP(V1)'     | 'EP(V1)'  | 'IC'  | ''      | ''                 | 'F09-MARK'     | 'PJT_PJT138K_revJULY-25-2013.pdf' | ''            | ''  | ''         | ''      | '20160617' | ''    
 'DMN53D0LDW-7' | 'SMLF'    | 'IC'     | 'BAM53D00003'(!)  = ''              | ''             | 'BAM53D00003'     |'SOT363_0-65_2X1-25XC'| 'TRANS MOSFET DMN53D0LDW(50V,0.36A,0.31W)' | 'DDS'   | 'DMN53D0LDW-7' | 'EP(V1)'     | 'EP(V1)'  | 'IC'  | ''      | 'DMN53D0LDW-7.msg' | 'F0G-MILLER'   | 'DDS_DMN53D0LDW-7.pdf'            | ''            | ''  | ''         | ''      | '20190717' | ''    
 'DMN53D0LDW-7' | 'SMLF'    | 'EMPTY'  | 'BAM53D00003'(!)  = ''              | ''             | 'BAM53D00003'     |'SOT363_0-65_2X1-25XC'| 'TRANS MOSFET DMN53D0LDW(50V,0.36A,0.31W)' | 'DDS'   | 'DMN53D0LDW-7' | 'EP(V1)'     | 'EP(V1)'  | 'IC'  | ''      | 'DMN53D0LDW-7.msg' | 'F0G-MILLER'   | 'DDS_DMN53D0LDW-7.pdf'            | ''            | ''  | ''         | ''      | '20190717' | ''    
 'PJT138KA'     | 'SMLF'    | 'IC'     | 'BAM138K0005'(!)  = ''              | ''             | 'BAM138K0005'     |'SOT363XD'| 'TRANS MOS PJT138KA(50V,0.36A,0.236W)'     | 'PJT'   | 'PJT138KA'     | 'EP(V1)'     | 'EP(V1)'  | 'IC'  | ''      | ''                 | 'S6S-KYLE'     | 'PJT_PJT138KA.pdf'                | ''            | ''  | ''         | ''      | '20210531' | ''    
 'PJT138KA'     | 'SMLF'    | 'EMPTY'  | 'BAM138K0005'(!)  = ''              | ''             | 'BAM138K0005'     |'SOT363XD'| 'TRANS MOS PJT138KA(50V,0.36A,0.236W)'     | 'PJT'   | 'PJT138KA'     | 'EP(V1)'     | 'EP(V1)'  | 'IC'  | ''      | ''                 | 'S6S-KYLE'     | 'PJT_PJT138KA.pdf'                | ''            | ''  | ''         | ''      | '20210531' | ''    
 'NX6008NBKS'   | 'SMLF'    | 'IC'     | 'BAM60080000'(!)  = ''              | ''             | 'BAM60080000'     |'SOT363XB'| 'TRANS MOS NX6008NBKS(60V, 0.22A,260W)'    | 'NXE'   | 'NX6008NBKS'   | 'EP(V1)'     | ''        | 'IC'  | ''      | ''                 | 'F0T-IVES'     | 'NXE_NX6008NBKS.pdf'              | ''            | ''  | ''         | ''      | '20210927' | ''    
 'NX6008NBKS'   | 'SMLF'    | 'EMPTY'  | 'BAM60080000'(!)  = ''              | ''             | 'BAM60080000'     |'SOT363XB'| 'TRANS MOS NX6008NBKS(60V, 0.22A,260W)'    | 'NXE'   | 'NX6008NBKS'   | 'EP(V1)'     | ''        | 'IC'  | ''      | ''                 | 'F0T-IVES'     | 'NXE_NX6008NBKS.pdf'              | ''            | ''  | ''         | ''      | '20210927' | ''    
 'PJT7838'      | 'SMLF'    | 'IC'     | 'BAM78380000'(!)  = ''              | ''             | 'BAM78380000'     |'SOT363XD'| 'TRANS MOS PJT7838(50V,400MA,350MW)'       | 'PJT'   | 'PJT7838'      | 'EP(V1)'     | 'EP(V1)'  | 'IC'  | ''      | ''                 | 'S3B-BERNIE'   | 'PJT_PJT7838.pdf'                 | ''            | ''  | ''         | ''      | '20221104' | ''    
 'PJT7838'      | 'SMLF'    | 'EMPTY'  | 'BAM78380000'(!)  = ''              | ''             | 'BAM78380000'     |'SOT363XD'| 'TRANS MOS PJT7838(50V,400MA,350MW)'       | 'PJT'   | 'PJT7838'      | 'EP(V1)'     | 'EP(V1)'  | 'IC'  | ''      | ''                 | 'S3B-BERNIE'   | 'PJT_PJT7838.pdf'                 | ''            | ''  | ''         | ''      | '20221104' | ''    
 '2N7002KDW'    | 'SMLF'    | 'IC'     | 'BAM70020047SEL1'(!) = ''              | ''               | 'BAM70020047SEL1' |'SOT363XD'| 'TRANS MOS 2N7002(60V115MA0.2W)SOT363SELA' | 'PJT'   | '2N7002KDW'    | 'EP(V1)'     | 'EP(V1)'  | 'IC'  | ''      | 'SEL_15QPN.xlsx'   | 'F06S-KENG-YU' | 'PJT_2N7002KDW.pdf'               | ''            | ''  | ''         | ''      | '20230626' | ''    
 '2N7002KDW'    | 'SMLF'    | 'EMPTY'  | 'BAM70020047SEL1'(!) = ''              | ''               | 'BAM70020047SEL1' |'SOT363XD'| 'TRANS MOS 2N7002(60V115MA0.2W)SOT363SELA' | 'PJT'   | '2N7002KDW'    | 'EP(V1)'     | 'EP(V1)'  | 'IC'  | ''      | 'SEL_15QPN.xlsx'   | 'F06S-KENG-YU' | 'PJT_2N7002KDW.pdf'               | ''            | ''  | ''         | ''      | '20230626' | ''    

END_PART

END.

